# S9S_MB_2U (Grand Teton) — schematic netlist excerpt (pin names and nets, part order shuffled) for the footprints in the layout excerpt that follows; sources: Cadence DE-HDL packaged netlist, KiCad conversion of 03242023_DA0F0TMBIJ0_F0T_Motherboard_J_brd_V01_OCP.brd

C141  Q_CAP_DIFFBUS  DIFF BUS_0.22UF 6.3V 20% X6S  pkg C0201  page 178 : \1\ = DMI_CPU0_PCH_TX_C_DN<6> ; \2\ = DMI_CPU0_PCH_TX_DN<6>
PC228_P0_8  Q_CAP  2.2UF 10V 10% X6S  pkg C0402  page 270 : A = PVCCIN_CPU0_PVCC ; B = GND

(kicad_pcb
	(version 20260206)
	(generator "pcbnew")
	(generator_version "10.0")
	(general
		(thickness 1.6)
		(legacy_teardrops no)
	)
	(paper "A4")
	(title_block
		(title "03242023_DA0F0TMBIJ0_F0T_Motherboard_J_brd_V01_OCP.brd")
		(comment 1 "Grand Teton / footprints 4068-4069 of 6105")
	)
	(layers
		(0 "F.Cu" signal "TOP")
		(4 "In1.Cu" signal "GND")
		(6 "In2.Cu" signal "IN1")
		(8 "In3.Cu" signal "GND1")
		(10 "In4.Cu" signal "IN2")
		(12 "In5.Cu" signal "GND2")
		(14 "In6.Cu" signal "IN3")
		(16 "In7.Cu" signal "GND3")
		(18 "In8.Cu" signal "VCC")
		(20 "In9.Cu" signal "VCC1")
		(22 "In10.Cu" signal "GND4")
		(24 "In11.Cu" signal "IN4")
		(26 "In12.Cu" signal "GND5")
		(28 "In13.Cu" signal "IN5")
		(30 "In14.Cu" signal "GND6")
		(32 "In15.Cu" signal "IN6")
		(34 "In16.Cu" signal "GND7")
		(2 "B.Cu" signal "BOTTOM")
		(9 "F.Adhes" user "F.Adhesive")
		(11 "B.Adhes" user "B.Adhesive")
		(13 "F.Paste" user "Package Geometry/Pastemask Top")
		(15 "B.Paste" user "Package Geometry/Pastemask Bottom")
		(5 "F.SilkS" user "Ref Des/Silkscreen Top")
		(7 "B.SilkS" user "Ref Des/Silkscreen Bottom")
		(1 "F.Mask" user "Board Geometry/Soldermask Top")
		(3 "B.Mask" user "Board Geometry/Soldermask Bottom")
		(17 "Dwgs.User" user "User.Drawings")
		(19 "Cmts.User" user "User.Comments")
		(21 "Eco1.User" user "User.Eco1")
		(23 "Eco2.User" user "User.Eco2")
		(25 "Edge.Cuts" user "Board Geometry/Outline")
		(27 "Margin" user)
		(31 "F.CrtYd" user "Package Geometry/Place Bound Top")
		(29 "B.CrtYd" user "Package Geometry/Place Bound Bottom")
		(35 "F.Fab" user "Ref Des/Assembly Top")
		(33 "B.Fab" user "Ref Des/Assembly Bottom")
	)
	(footprint ""
		(layer "F.Cu")
		(at 382.165352 -342.726264 -90)
		(property "Reference" "PC228_P0_8"
			(at 0 0 270)
			(layer "F.SilkS")
			(hide yes)
			(effects
				(font
					(size 1.27 1.27)
				)
			)
		)
		(property "Value" ""
			(at 0 0 270)
			(layer "F.Fab")
			(effects
				(font
					(size 1.27 1.27)
				)
			)
		)
		(duplicate_pad_numbers_are_jumpers no)
		(fp_line
			(start -0.7874 0.4064)
			(end -0.7874 -0.4064)
			(stroke
				(width 0.1524)
				(type default)
			)
			(layer "F.SilkS")
		)
		(fp_line
			(start 0.7874 0.4064)
			(end -0.7874 0.4064)
			(stroke
				(width 0.1524)
				(type default)
			)
			(layer "F.SilkS")
		)
		(fp_line
			(start -0.7874 -0.4064)
			(end 0.7874 -0.4064)
			(stroke
				(width 0.1524)
				(type default)
			)
			(layer "F.SilkS")
		)
		(fp_line
			(start 0.7874 -0.4064)
			(end 0.7874 0.4064)
			(stroke
				(width 0.1524)
				(type default)
			)
			(layer "F.SilkS")
		)
		(fp_line
			(start -0.67945 0.3048)
			(end -0.67945 -0.305054)
			(stroke
				(width 0.1)
				(type default)
			)
			(layer "F.Fab")
		)
		(fp_line
			(start -0.12065 0.3048)
			(end -0.67945 0.3048)
			(stroke
				(width 0.1)
				(type default)
			)
			(layer "F.Fab")
		)
		(fp_line
			(start 0.120396 0.3048)
			(end 0.120396 0.2794)
			(stroke
				(width 0.1)
				(type default)
			)
			(layer "F.Fab")
		)
		(fp_line
			(start 0.67945 0.3048)
			(end 0.120396 0.3048)
			(stroke
				(width 0.1)
				(type default)
			)
			(layer "F.Fab")
		)
		(fp_line
			(start -0.12065 0.2794)
			(end -0.12065 0.3048)
			(stroke
				(width 0.1)
				(type default)
			)
			(layer "F.Fab")
		)
		(fp_line
			(start 0.120396 0.2794)
			(end -0.12065 0.2794)
			(stroke
				(width 0.1)
				(type default)
			)
			(layer "F.Fab")
		)
		(fp_line
			(start -0.12065 -0.2794)
			(end 0.12065 -0.2794)
			(stroke
				(width 0.1)
				(type default)
			)
			(layer "F.Fab")
		)
		(fp_line
			(start 0.12065 -0.2794)
			(end 0.12065 -0.3048)
			(stroke
				(width 0.1)
				(type default)
			)
			(layer "F.Fab")
		)
		(fp_line
			(start 0.12065 -0.3048)
			(end 0.67945 -0.3048)
			(stroke
				(width 0.1)
				(type default)
			)
			(layer "F.Fab")
		)
		(fp_line
			(start 0.67945 -0.3048)
			(end 0.67945 0.3048)
			(stroke
				(width 0.1)
				(type default)
			)
			(layer "F.Fab")
		)
		(fp_line
			(start -0.67945 -0.305054)
			(end -0.12065 -0.305054)
			(stroke
				(width 0.1)
				(type default)
			)
			(layer "F.Fab")
		)
		(fp_line
			(start -0.12065 -0.305054)
			(end -0.12065 -0.2794)
			(stroke
				(width 0.1)
				(type default)
			)
			(layer "F.Fab")
		)
		(pad "1" smd circle
			(at -0.40005 0 270)
			(size 0 0)
			(layers "F.Cu" "F.Mask" "F.Paste")
			(net "PVCCIN_CPU0_PVCC")
		)
		(pad "2" smd circle
			(at 0.40005 0 270)
			(size 0 0)
			(layers "F.Cu" "F.Mask" "F.Paste")
			(net "GND")
		)
	)
	(footprint ""
		(layer "F.Cu")
		(at 349.0849 -62.398148)
		(property "Reference" "C141"
			(at 0 0 0)
			(layer "F.SilkS")
			(hide yes)
			(effects
				(font
					(size 1.27 1.27)
				)
			)
		)
		(property "Value" ""
			(at 0 0 0)
			(layer "F.Fab")
			(effects
				(font
					(size 1.27 1.27)
				)
			)
		)
		(duplicate_pad_numbers_are_jumpers no)
		(fp_line
			(start -0.299974 -0.150114)
			(end 0.299974 -0.150114)
			(stroke
				(width 0.1)
				(type default)
			)
			(layer "F.Fab")
		)
		(fp_line
			(start -0.299974 0.150114)
			(end -0.299974 -0.150114)
			(stroke
				(width 0.1)
				(type default)
			)
			(layer "F.Fab")
		)
		(fp_line
			(start 0.299974 -0.150114)
			(end 0.299974 0.150114)
			(stroke
				(width 0.1)
				(type default)
			)
			(layer "F.Fab")
		)
		(fp_line
			(start 0.299974 0.150114)
			(end -0.299974 0.150114)
			(stroke
				(width 0.1)
				(type default)
			)
			(layer "F.Fab")
		)
		(pad "1" smd rect
			(at -0.2667 0)
			(size 0.3048 0.381)
			(layers "F.Cu" "F.Mask" "F.Paste")
			(net "DMI_CPU0_PCH_TX_C_DN<6>")
		)
		(pad "2" smd rect
			(at 0.2667 0)
			(size 0.3048 0.381)
			(layers "F.Cu" "F.Mask" "F.Paste")
			(net "DMI_CPU0_PCH_TX_DN<6>")
		)
		(zone
			(layer "In1.Cu")
			(hatch none 0.5)
			(connect_pads
				(clearance 0)
			)
			(min_thickness 0.25)
			(keepout
				(tracks not_allowed)
				(vias allowed)
				(pads allowed)
				(copperpour not_allowed)
				(footprints allowed)
			)
			(placement
				(enabled no)
				(sheetname "")
			)
			(fill
				(thermal_gap 0.5)
				(thermal_bridge_width 0.5)
				(island_removal_mode 0)
			)
			(polygon
				(pts
					(arc
						(start 348.6912 -62.156848)
						(mid 348.637318 -62.179166)
						(end 348.615 -62.233048)
					)
					(arc
						(start 348.615 -62.563248)
						(mid 348.637318 -62.61713)
						(end 348.6912 -62.639448)
					)
					(arc
						(start 348.9452 -62.639448)
						(mid 348.999082 -62.61713)
						(end 349.0214 -62.563248)
					)
					(arc
						(start 349.0214 -62.233048)
						(mid 348.999082 -62.179166)
						(end 348.9452 -62.156848)
					)
				)
			)
		)
		(zone
			(layer "In1.Cu")
			(hatch none 0.5)
			(connect_pads
				(clearance 0)
			)
			(min_thickness 0.25)
			(keepout
				(tracks not_allowed)
				(vias allowed)
				(pads allowed)
				(copperpour not_allowed)
				(footprints allowed)
			)
			(placement
				(enabled no)
				(sheetname "")
			)
			(fill
				(thermal_gap 0.5)
				(thermal_bridge_width 0.5)
				(island_removal_mode 0)
			)
			(polygon
				(pts
					(arc
						(start 349.2246 -62.156848)
						(mid 349.170718 -62.179166)
						(end 349.1484 -62.233048)
					)
					(arc
						(start 349.1484 -62.563248)
						(mid 349.170718 -62.61713)
						(end 349.2246 -62.639448)
					)
					(arc
						(start 349.4786 -62.639448)
						(mid 349.532482 -62.61713)
						(end 349.5548 -62.563248)
					)
					(arc
						(start 349.5548 -62.233048)
						(mid 349.532482 -62.179166)
						(end 349.4786 -62.156848)
					)
				)
			)
		)
	)
)
